# S9S_MB_2U (Grand Teton) — schematic netlist excerpt (pin names and nets, part order shuffled) for the footprints in the layout excerpt that follows; sources: Cadence DE-HDL packaged netlist, KiCad conversion of 03242023_DA0F0TMBIJ0_F0T_Motherboard_J_brd_V01_OCP.brd

PC1271  Q_CAP  470PF 50V 10% X7R  pkg 0402  page 274 : A = PVCCFA_EHV_CPU0_BTSEN ; B = GND
PC1573  Q_CAPP  330UF 2V 35% SPCAP  pkg SMLF  page 275 : A = PVCCINFAON_CPU0 ; B = GND

(kicad_pcb
	(version 20260206)
	(generator "pcbnew")
	(generator_version "10.0")
	(general
		(thickness 1.6)
		(legacy_teardrops no)
	)
	(paper "A4")
	(title_block
		(title "03242023_DA0F0TMBIJ0_F0T_Motherboard_J_brd_V01_OCP.brd")
		(comment 1 "Grand Teton / footprints 4710-4711 of 6105")
	)
	(layers
		(0 "F.Cu" signal "TOP")
		(4 "In1.Cu" signal "GND")
		(6 "In2.Cu" signal "IN1")
		(8 "In3.Cu" signal "GND1")
		(10 "In4.Cu" signal "IN2")
		(12 "In5.Cu" signal "GND2")
		(14 "In6.Cu" signal "IN3")
		(16 "In7.Cu" signal "GND3")
		(18 "In8.Cu" signal "VCC")
		(20 "In9.Cu" signal "VCC1")
		(22 "In10.Cu" signal "GND4")
		(24 "In11.Cu" signal "IN4")
		(26 "In12.Cu" signal "GND5")
		(28 "In13.Cu" signal "IN5")
		(30 "In14.Cu" signal "GND6")
		(32 "In15.Cu" signal "IN6")
		(34 "In16.Cu" signal "GND7")
		(2 "B.Cu" signal "BOTTOM")
		(9 "F.Adhes" user "F.Adhesive")
		(11 "B.Adhes" user "B.Adhesive")
		(13 "F.Paste" user "Package Geometry/Pastemask Top")
		(15 "B.Paste" user "Package Geometry/Pastemask Bottom")
		(5 "F.SilkS" user "Ref Des/Silkscreen Top")
		(7 "B.SilkS" user "Ref Des/Silkscreen Bottom")
		(1 "F.Mask" user "Board Geometry/Soldermask Top")
		(3 "B.Mask" user "Board Geometry/Soldermask Bottom")
		(17 "Dwgs.User" user "User.Drawings")
		(19 "Cmts.User" user "User.Comments")
		(21 "Eco1.User" user "User.Eco1")
		(23 "Eco2.User" user "User.Eco2")
		(25 "Edge.Cuts" user "Board Geometry/Outline")
		(27 "Margin" user)
		(31 "F.CrtYd" user "Package Geometry/Place Bound Top")
		(29 "B.CrtYd" user "Package Geometry/Place Bound Bottom")
		(35 "F.Fab" user "Ref Des/Assembly Top")
		(33 "B.Fab" user "Ref Des/Assembly Bottom")
	)
	(footprint ""
		(layer "B.Cu")
		(at 423.807382 -137.07872 180)
		(property "Reference" "PC1271"
			(at 0 0 0)
			(layer "B.SilkS")
			(hide yes)
			(effects
				(font
					(size 1.27 1.27)
				)
				(justify mirror)
			)
		)
		(property "Value" ""
			(at 0 0 0)
			(layer "B.Fab")
			(effects
				(font
					(size 1.27 1.27)
				)
				(justify mirror)
			)
		)
		(duplicate_pad_numbers_are_jumpers no)
		(fp_line
			(start 0.7874 0.4064)
			(end 0.7874 -0.4064)
			(stroke
				(width 0.1524)
				(type default)
			)
			(layer "B.SilkS")
		)
		(fp_line
			(start 0.7874 -0.4064)
			(end -0.7874 -0.4064)
			(stroke
				(width 0.1524)
				(type default)
			)
			(layer "B.SilkS")
		)
		(fp_line
			(start -0.7874 0.4064)
			(end 0.7874 0.4064)
			(stroke
				(width 0.1524)
				(type default)
			)
			(layer "B.SilkS")
		)
		(fp_line
			(start -0.7874 -0.4064)
			(end -0.7874 0.4064)
			(stroke
				(width 0.1524)
				(type default)
			)
			(layer "B.SilkS")
		)
		(fp_line
			(start 0.67945 0.3048)
			(end 0.67945 -0.305054)
			(stroke
				(width 0.1)
				(type default)
			)
			(layer "B.Fab")
		)
		(fp_line
			(start 0.67945 -0.305054)
			(end 0.12065 -0.305054)
			(stroke
				(width 0.1)
				(type default)
			)
			(layer "B.Fab")
		)
		(fp_line
			(start 0.12065 0.3048)
			(end 0.67945 0.3048)
			(stroke
				(width 0.1)
				(type default)
			)
			(layer "B.Fab")
		)
		(fp_line
			(start 0.12065 0.2794)
			(end 0.12065 0.3048)
			(stroke
				(width 0.1)
				(type default)
			)
			(layer "B.Fab")
		)
		(fp_line
			(start 0.12065 -0.2794)
			(end -0.12065 -0.2794)
			(stroke
				(width 0.1)
				(type default)
			)
			(layer "B.Fab")
		)
		(fp_line
			(start 0.12065 -0.305054)
			(end 0.12065 -0.2794)
			(stroke
				(width 0.1)
				(type default)
			)
			(layer "B.Fab")
		)
		(fp_line
			(start -0.120396 0.3048)
			(end -0.120396 0.2794)
			(stroke
				(width 0.1)
				(type default)
			)
			(layer "B.Fab")
		)
		(fp_line
			(start -0.120396 0.2794)
			(end 0.12065 0.2794)
			(stroke
				(width 0.1)
				(type default)
			)
			(layer "B.Fab")
		)
		(fp_line
			(start -0.12065 -0.2794)
			(end -0.12065 -0.3048)
			(stroke
				(width 0.1)
				(type default)
			)
			(layer "B.Fab")
		)
		(fp_line
			(start -0.12065 -0.3048)
			(end -0.67945 -0.3048)
			(stroke
				(width 0.1)
				(type default)
			)
			(layer "B.Fab")
		)
		(fp_line
			(start -0.67945 0.3048)
			(end -0.120396 0.3048)
			(stroke
				(width 0.1)
				(type default)
			)
			(layer "B.Fab")
		)
		(fp_line
			(start -0.67945 -0.3048)
			(end -0.67945 0.3048)
			(stroke
				(width 0.1)
				(type default)
			)
			(layer "B.Fab")
		)
		(pad "1" smd circle
			(at 0.40005 0)
			(size 0 0)
			(layers "B.Cu" "B.Mask" "B.Paste")
			(net "PVCCFA_EHV_CPU0_BTSEN")
		)
		(pad "2" smd circle
			(at -0.40005 0)
			(size 0 0)
			(layers "B.Cu" "B.Mask" "B.Paste")
			(net "GND")
		)
	)
	(footprint ""
		(layer "B.Cu")
		(at 409.284932 -179.457858 180)
		(property "Reference" "PC1573"
			(at 0 0 0)
			(layer "B.SilkS")
			(hide yes)
			(effects
				(font
					(size 1.27 1.27)
				)
				(justify mirror)
			)
		)
		(property "Value" ""
			(at 0 0 0)
			(layer "B.Fab")
			(effects
				(font
					(size 1.27 1.27)
				)
				(justify mirror)
			)
		)
		(duplicate_pad_numbers_are_jumpers no)
		(fp_line
			(start 4.84378 -2.150618)
			(end 4.842256 2.163064)
			(stroke
				(width 0.1524)
				(type default)
			)
			(layer "B.SilkS")
		)
		(fp_line
			(start 4.84378 -2.150618)
			(end 4.53898 -2.150618)
			(stroke
				(width 0.1524)
				(type default)
			)
			(layer "B.SilkS")
		)
		(fp_line
			(start 4.83108 2.150364)
			(end 4.447794 2.149348)
			(stroke
				(width 0.1524)
				(type default)
			)
			(layer "B.SilkS")
		)
		(fp_line
			(start 4.69138 -2.150618)
			(end 4.692396 2.161032)
			(stroke
				(width 0.1524)
				(type default)
			)
			(layer "B.SilkS")
		)
		(fp_line
			(start 4.53898 2.15011)
			(end 4.53898 -2.15011)
			(stroke
				(width 0.1524)
				(type default)
			)
			(layer "B.SilkS")
		)
		(fp_line
			(start 4.53898 -2.15011)
			(end -4.53898 -2.15011)
			(stroke
				(width 0.1524)
				(type default)
			)
			(layer "B.SilkS")
		)
		(fp_line
			(start 4.53898 -2.150618)
			(end 4.539742 2.152142)
			(stroke
				(width 0.1524)
				(type default)
			)
			(layer "B.SilkS")
		)
		(fp_line
			(start -4.53898 2.15011)
			(end 4.53898 2.15011)
			(stroke
				(width 0.1524)
				(type default)
			)
			(layer "B.SilkS")
		)
		(fp_line
			(start -4.53898 -2.15011)
			(end -4.53898 2.15011)
			(stroke
				(width 0.1524)
				(type default)
			)
			(layer "B.SilkS")
		)
		(fp_line
			(start 3.64998 2.15011)
			(end 3.64998 -2.15011)
			(stroke
				(width 0.1)
				(type default)
			)
			(layer "B.Fab")
		)
		(fp_line
			(start 3.64998 -2.15011)
			(end -3.64998 -2.15011)
			(stroke
				(width 0.1)
				(type default)
			)
			(layer "B.Fab")
		)
		(fp_line
			(start -3.64998 2.15011)
			(end 3.64998 2.15011)
			(stroke
				(width 0.1)
				(type default)
			)
			(layer "B.Fab")
		)
		(fp_line
			(start -3.64998 -2.15011)
			(end -3.64998 2.15011)
			(stroke
				(width 0.1)
				(type default)
			)
			(layer "B.Fab")
		)
		(fp_text user "+"
			(at 6.214872 -0.337058 180)
			(unlocked yes)
			(layer "B.SilkS")
			(effects
				(font
					(size 1.905 1.4224)
					(thickness 0.1524)
				)
				(justify left mirror)
			)
		)
		(fp_text user "-"
			(at -5.123688 0.89154 180)
			(unlocked yes)
			(layer "B.SilkS")
			(effects
				(font
					(size 1.905 1.4224)
					(thickness 0.1524)
				)
				(justify left mirror)
			)
		)
		(fp_text user "+"
			(at 6.214872 -0.337058 180)
			(unlocked yes)
			(layer "B.Fab")
			(effects
				(font
					(size 1.905 1.4224)
					(thickness 0.1524)
				)
				(justify left mirror)
			)
		)
		(fp_text user "-"
			(at -4.313174 -0.094488 180)
			(unlocked yes)
			(layer "B.Fab")
			(effects
				(font
					(size 1.905 1.4224)
					(thickness 0.1524)
				)
				(justify left mirror)
			)
		)
		(pad "1" smd rect
			(at 3.199892 0)
			(size 2.413 2.8194)
			(layers "B.Cu" "B.Mask" "B.Paste")
			(net "PVCCINFAON_CPU0")
		)
		(pad "2" smd rect
			(at -3.199892 0)
			(size 2.413 2.8194)
			(layers "B.Cu" "B.Mask" "B.Paste")
			(net "GND")
		)
	)
)
